(kicad_pcb
	(version 20260206)
	(generator "pcbnew")
	(generator_version "10.0")
	(general
		(thickness 1.6)
		(legacy_teardrops no)
	)
	(paper "A4")
	(title_block
		(title "04192023_DAF0TMB3IC0_F0TG_MB_C_brd_V02_OCP.brd")
		(comment 1 "Grand Teton / footprints 57-64 of 8354")
	)
	(layers
		(0 "F.Cu" signal "TOP")
		(4 "In1.Cu" signal "GND")
		(6 "In2.Cu" signal "IN1")
		(8 "In3.Cu" signal "GND1")
		(10 "In4.Cu" signal "IN2")
		(12 "In5.Cu" signal "GND2")
		(14 "In6.Cu" signal "IN3")
		(16 "In7.Cu" signal "GND3")
		(18 "In8.Cu" signal "VCC")
		(20 "In9.Cu" signal "VCC1")
		(22 "In10.Cu" signal "GND4")
		(24 "In11.Cu" signal "IN4")
		(26 "In12.Cu" signal "GND5")
		(28 "In13.Cu" signal "IN5")
		(30 "In14.Cu" signal "GND6")
		(32 "In15.Cu" signal "IN6")
		(34 "In16.Cu" signal "GND7")
		(2 "B.Cu" signal "BOTTOM")
		(9 "F.Adhes" user "F.Adhesive")
		(11 "B.Adhes" user "B.Adhesive")
		(13 "F.Paste" user "Package Geometry/Pastemask Top")
		(15 "B.Paste" user "Package Geometry/Pastemask Bottom")
		(5 "F.SilkS" user "Ref Des/Silkscreen Top")
		(7 "B.SilkS" user "Ref Des/Silkscreen Bottom")
		(1 "F.Mask" user "Board Geometry/Soldermask Top")
		(3 "B.Mask" user "Board Geometry/Soldermask Bottom")
		(17 "Dwgs.User" user "User.Drawings")
		(19 "Cmts.User" user "User.Comments")
		(21 "Eco1.User" user "User.Eco1")
		(23 "Eco2.User" user "User.Eco2")
		(25 "Edge.Cuts" user "Board Geometry/Outline")
		(27 "Margin" user)
		(31 "F.CrtYd" user "Package Geometry/Place Bound Top")
		(29 "B.CrtYd" user "Package Geometry/Place Bound Bottom")
		(35 "F.Fab" user "Ref Des/Assembly Top")
		(33 "B.Fab" user "Ref Des/Assembly Bottom")
	)
	(footprint ""
		(layer "F.Cu")
		(at 423.796206 -404.0124 -90)
		(property "Reference" "R1047"
			(at 0 0 270)
			(layer "F.SilkS")
			(hide yes)
			(effects
				(font
					(size 1.27 1.27)
				)
			)
		)
		(property "Value" ""
			(at 0 0 270)
			(layer "F.Fab")
			(effects
				(font
					(size 1.27 1.27)
				)
			)
		)
		(duplicate_pad_numbers_are_jumpers no)
		(fp_line
			(start -0.32512 0.175006)
			(end -0.32512 -0.175006)
			(stroke
				(width 0.1)
				(type default)
			)
			(layer "F.Fab")
		)
		(fp_line
			(start 0.32512 0.175006)
			(end -0.32512 0.175006)
			(stroke
				(width 0.1)
				(type default)
			)
			(layer "F.Fab")
		)
		(fp_line
			(start -0.32512 -0.175006)
			(end 0.32512 -0.175006)
			(stroke
				(width 0.1)
				(type default)
			)
			(layer "F.Fab")
		)
		(fp_line
			(start 0.32512 -0.175006)
			(end 0.32512 0.175006)
			(stroke
				(width 0.1)
				(type default)
			)
			(layer "F.Fab")
		)
		(pad "1" smd rect
			(at -0.2667 0 270)
			(size 0.3048 0.381)
			(layers "F.Cu" "F.Mask" "F.Paste")
			(net "RST_RT_CPU0_P2_PERST_N")
		)
		(pad "2" smd rect
			(at 0.2667 0 90)
			(size 0.3048 0.381)
			(layers "F.Cu" "F.Mask" "F.Paste")
			(net "RST_RT_CPU0_P2_PERST_R_N")
		)
	)
	(footprint ""
		(layer "F.Cu")
		(at 89.564972 -68.02374 90)
		(property "Reference" "PC2142"
			(at 0 0 90)
			(layer "F.SilkS")
			(hide yes)
			(effects
				(font
					(size 1.27 1.27)
				)
			)
		)
		(property "Value" ""
			(at 0 0 90)
			(layer "F.Fab")
			(effects
				(font
					(size 1.27 1.27)
				)
			)
		)
		(duplicate_pad_numbers_are_jumpers no)
		(fp_line
			(start 1.524 -0.762)
			(end 1.524 0.762)
			(stroke
				(width 0.1524)
				(type default)
			)
			(layer "F.SilkS")
		)
		(fp_line
			(start -1.524 -0.762)
			(end 1.524 -0.762)
			(stroke
				(width 0.1524)
				(type default)
			)
			(layer "F.SilkS")
		)
		(fp_line
			(start 1.524 0.762)
			(end -1.524 0.762)
			(stroke
				(width 0.1524)
				(type default)
			)
			(layer "F.SilkS")
		)
		(fp_line
			(start -1.524 0.762)
			(end -1.524 -0.762)
			(stroke
				(width 0.1524)
				(type default)
			)
			(layer "F.SilkS")
		)
		(fp_line
			(start 1.1049 -0.724916)
			(end -1.1049 -0.724916)
			(stroke
				(width 0.1)
				(type default)
			)
			(layer "F.Fab")
		)
		(fp_line
			(start -1.1049 -0.724916)
			(end -1.1049 0.724916)
			(stroke
				(width 0.1)
				(type default)
			)
			(layer "F.Fab")
		)
		(fp_line
			(start 1.1049 0.724916)
			(end 1.1049 -0.724916)
			(stroke
				(width 0.1)
				(type default)
			)
			(layer "F.Fab")
		)
		(fp_line
			(start -1.1049 0.724916)
			(end 1.1049 0.724916)
			(stroke
				(width 0.1)
				(type default)
			)
			(layer "F.Fab")
		)
		(pad "1" smd rect
			(at -0.889 0 270)
			(size 1.016 1.27)
			(layers "F.Cu" "F.Mask" "F.Paste")
			(net "P3V3_OCP_V3_2_R")
		)
		(pad "2" smd rect
			(at 0.889 0 270)
			(size 1.016 1.27)
			(layers "F.Cu" "F.Mask" "F.Paste")
			(net "GND")
		)
	)
	(footprint ""
		(layer "F.Cu")
		(at 335.114646 -404.873206 -90)
		(property "Reference" "R1024"
			(at 0 0 270)
			(layer "F.SilkS")
			(hide yes)
			(effects
				(font
					(size 1.27 1.27)
				)
			)
		)
		(property "Value" ""
			(at 0 0 270)
			(layer "F.Fab")
			(effects
				(font
					(size 1.27 1.27)
				)
			)
		)
		(duplicate_pad_numbers_are_jumpers no)
		(fp_line
			(start -0.32512 0.175006)
			(end -0.32512 -0.175006)
			(stroke
				(width 0.1)
				(type default)
			)
			(layer "F.Fab")
		)
		(fp_line
			(start 0.32512 0.175006)
			(end -0.32512 0.175006)
			(stroke
				(width 0.1)
				(type default)
			)
			(layer "F.Fab")
		)
		(fp_line
			(start -0.32512 -0.175006)
			(end 0.32512 -0.175006)
			(stroke
				(width 0.1)
				(type default)
			)
			(layer "F.Fab")
		)
		(fp_line
			(start 0.32512 -0.175006)
			(end 0.32512 0.175006)
			(stroke
				(width 0.1)
				(type default)
			)
			(layer "F.Fab")
		)
		(pad "1" smd rect
			(at -0.2667 0 270)
			(size 0.3048 0.381)
			(layers "F.Cu" "F.Mask" "F.Paste")
			(net "P1V8_CPU0_RT_1D")
		)
		(pad "2" smd rect
			(at 0.2667 0 90)
			(size 0.3048 0.381)
			(layers "F.Cu" "F.Mask" "F.Paste")
			(net "JTAG_TEST_MODE_RT_CPU0_P1")
		)
	)
	(footprint ""
		(layer "F.Cu")
		(at 160.441386 -117.206014 180)
		(property "Reference" "R2233"
			(at 0 0 180)
			(layer "F.SilkS")
			(hide yes)
			(effects
				(font
					(size 1.27 1.27)
				)
			)
		)
		(property "Value" ""
			(at 0 0 180)
			(layer "F.Fab")
			(effects
				(font
					(size 1.27 1.27)
				)
			)
		)
		(duplicate_pad_numbers_are_jumpers no)
		(fp_line
			(start 0.7874 0.4064)
			(end -0.7874 0.4064)
			(stroke
				(width 0.1524)
				(type default)
			)
			(layer "F.SilkS")
		)
		(fp_line
			(start 0.7874 -0.4064)
			(end 0.7874 0.4064)
			(stroke
				(width 0.1524)
				(type default)
			)
			(layer "F.SilkS")
		)
		(fp_line
			(start -0.7874 0.4064)
			(end -0.7874 -0.4064)
			(stroke
				(width 0.1524)
				(type default)
			)
			(layer "F.SilkS")
		)
		(fp_line
			(start -0.7874 -0.4064)
			(end 0.7874 -0.4064)
			(stroke
				(width 0.1524)
				(type default)
			)
			(layer "F.SilkS")
		)
		(fp_line
			(start 0.67945 0.3048)
			(end 0.120396 0.3048)
			(stroke
				(width 0.1)
				(type default)
			)
			(layer "F.Fab")
		)
		(fp_line
			(start 0.67945 -0.3048)
			(end 0.67945 0.3048)
			(stroke
				(width 0.1)
				(type default)
			)
			(layer "F.Fab")
		)
		(fp_line
			(start 0.12065 -0.2794)
			(end 0.12065 -0.3048)
			(stroke
				(width 0.1)
				(type default)
			)
			(layer "F.Fab")
		)
		(fp_line
			(start 0.12065 -0.3048)
			(end 0.67945 -0.3048)
			(stroke
				(width 0.1)
				(type default)
			)
			(layer "F.Fab")
		)
		(fp_line
			(start 0.120396 0.3048)
			(end 0.120396 0.2794)
			(stroke
				(width 0.1)
				(type default)
			)
			(layer "F.Fab")
		)
		(fp_line
			(start 0.120396 0.2794)
			(end -0.12065 0.2794)
			(stroke
				(width 0.1)
				(type default)
			)
			(layer "F.Fab")
		)
		(fp_line
			(start -0.12065 0.3048)
			(end -0.67945 0.3048)
			(stroke
				(width 0.1)
				(type default)
			)
			(layer "F.Fab")
		)
		(fp_line
			(start -0.12065 0.2794)
			(end -0.12065 0.3048)
			(stroke
				(width 0.1)
				(type default)
			)
			(layer "F.Fab")
		)
		(fp_line
			(start -0.12065 -0.2794)
			(end 0.12065 -0.2794)
			(stroke
				(width 0.1)
				(type default)
			)
			(layer "F.Fab")
		)
		(fp_line
			(start -0.12065 -0.305054)
			(end -0.12065 -0.2794)
			(stroke
				(width 0.1)
				(type default)
			)
			(layer "F.Fab")
		)
		(fp_line
			(start -0.67945 0.3048)
			(end -0.67945 -0.305054)
			(stroke
				(width 0.1)
				(type default)
			)
			(layer "F.Fab")
		)
		(fp_line
			(start -0.67945 -0.305054)
			(end -0.12065 -0.305054)
			(stroke
				(width 0.1)
				(type default)
			)
			(layer "F.Fab")
		)
		(pad "1" smd circle
			(at -0.40005 0 180)
			(size 0 0)
			(layers "F.Cu" "F.Mask" "F.Paste")
			(net "P3V3_AUX")
		)
		(pad "2" smd circle
			(at 0.40005 0 180)
			(size 0 0)
			(layers "F.Cu" "F.Mask" "F.Paste")
			(net "FM_UV_ADR_TRIGGER_N")
		)
	)
	(footprint ""
		(layer "F.Cu")
		(at 23.433278 -437.599074 -90)
		(property "Reference" "R2987"
			(at 0 0 270)
			(layer "F.SilkS")
			(hide yes)
			(effects
				(font
					(size 1.27 1.27)
				)
			)
		)
		(property "Value" ""
			(at 0 0 270)
			(layer "F.Fab")
			(effects
				(font
					(size 1.27 1.27)
				)
			)
		)
		(duplicate_pad_numbers_are_jumpers no)
		(fp_line
			(start -0.7874 0.4064)
			(end -0.7874 -0.4064)
			(stroke
				(width 0.1524)
				(type default)
			)
			(layer "F.SilkS")
		)
		(fp_line
			(start 0.7874 0.4064)
			(end -0.7874 0.4064)
			(stroke
				(width 0.1524)
				(type default)
			)
			(layer "F.SilkS")
		)
		(fp_line
			(start -0.7874 -0.4064)
			(end 0.7874 -0.4064)
			(stroke
				(width 0.1524)
				(type default)
			)
			(layer "F.SilkS")
		)
		(fp_line
			(start 0.7874 -0.4064)
			(end 0.7874 0.4064)
			(stroke
				(width 0.1524)
				(type default)
			)
			(layer "F.SilkS")
		)
		(fp_line
			(start -0.67945 0.3048)
			(end -0.67945 -0.305054)
			(stroke
				(width 0.1)
				(type default)
			)
			(layer "F.Fab")
		)
		(fp_line
			(start -0.12065 0.3048)
			(end -0.67945 0.3048)
			(stroke
				(width 0.1)
				(type default)
			)
			(layer "F.Fab")
		)
		(fp_line
			(start 0.120396 0.3048)
			(end 0.120396 0.2794)
			(stroke
				(width 0.1)
				(type default)
			)
			(layer "F.Fab")
		)
		(fp_line
			(start 0.67945 0.3048)
			(end 0.120396 0.3048)
			(stroke
				(width 0.1)
				(type default)
			)
			(layer "F.Fab")
		)
		(fp_line
			(start -0.12065 0.2794)
			(end -0.12065 0.3048)
			(stroke
				(width 0.1)
				(type default)
			)
			(layer "F.Fab")
		)
		(fp_line
			(start 0.120396 0.2794)
			(end -0.12065 0.2794)
			(stroke
				(width 0.1)
				(type default)
			)
			(layer "F.Fab")
		)
		(fp_line
			(start -0.12065 -0.2794)
			(end 0.12065 -0.2794)
			(stroke
				(width 0.1)
				(type default)
			)
			(layer "F.Fab")
		)
		(fp_line
			(start 0.12065 -0.2794)
			(end 0.12065 -0.3048)
			(stroke
				(width 0.1)
				(type default)
			)
			(layer "F.Fab")
		)
		(fp_line
			(start 0.12065 -0.3048)
			(end 0.67945 -0.3048)
			(stroke
				(width 0.1)
				(type default)
			)
			(layer "F.Fab")
		)
		(fp_line
			(start 0.67945 -0.3048)
			(end 0.67945 0.3048)
			(stroke
				(width 0.1)
				(type default)
			)
			(layer "F.Fab")
		)
		(fp_line
			(start -0.67945 -0.305054)
			(end -0.12065 -0.305054)
			(stroke
				(width 0.1)
				(type default)
			)
			(layer "F.Fab")
		)
		(fp_line
			(start -0.12065 -0.305054)
			(end -0.12065 -0.2794)
			(stroke
				(width 0.1)
				(type default)
			)
			(layer "F.Fab")
		)
		(pad "1" smd circle
			(at -0.40005 0 270)
			(size 0 0)
			(layers "F.Cu" "F.Mask" "F.Paste")
			(net "SMB_2_BMC_GPU_R_SDA")
		)
		(pad "2" smd circle
			(at 0.40005 0 270)
			(size 0 0)
			(layers "F.Cu" "F.Mask" "F.Paste")
			(net "SMB_2_BMC_GPU_BUF_R_SDA")
		)
	)
	(footprint ""
		(layer "F.Cu")
		(at 73.15073 -392.521694)
		(property "Reference" "L6"
			(at -2.3876 -2.969768 0)
			(unlocked yes)
			(layer "F.SilkS")
			(effects
				(font
					(size 0.7874 0.5842)
					(thickness 0.1524)
				)
				(justify left)
			)
		)
		(property "Value" ""
			(at 0 0 0)
			(layer "F.Fab")
			(effects
				(font
					(size 1.27 1.27)
				)
			)
		)
		(duplicate_pad_numbers_are_jumpers no)
		(fp_line
			(start -2.249932 -2.249932)
			(end 2.249932 -2.249932)
			(stroke
				(width 0.1524)
				(type default)
			)
			(layer "F.SilkS")
		)
		(fp_line
			(start -2.249932 -1.3843)
			(end -2.249932 -2.249932)
			(stroke
				(width 0.1524)
				(type default)
			)
			(layer "F.SilkS")
		)
		(fp_line
			(start -2.249932 2.249932)
			(end -2.249932 1.3843)
			(stroke
				(width 0.1524)
				(type default)
			)
			(layer "F.SilkS")
		)
		(fp_line
			(start 2.249932 -2.249932)
			(end 2.249932 -1.3843)
			(stroke
				(width 0.1524)
				(type default)
			)
			(layer "F.SilkS")
		)
		(fp_line
			(start 2.249932 1.3843)
			(end 2.249932 2.249932)
			(stroke
				(width 0.1524)
				(type default)
			)
			(layer "F.SilkS")
		)
		(fp_line
			(start 2.249932 2.249932)
			(end -2.249932 2.249932)
			(stroke
				(width 0.1524)
				(type default)
			)
			(layer "F.SilkS")
		)
		(fp_line
			(start -2.249932 -2.249932)
			(end 2.249932 -2.249932)
			(stroke
				(width 0.1)
				(type default)
			)
			(layer "F.Fab")
		)
		(fp_line
			(start -2.249932 2.249932)
			(end -2.249932 -2.249932)
			(stroke
				(width 0.1)
				(type default)
			)
			(layer "F.Fab")
		)
		(fp_line
			(start 2.249932 -2.249932)
			(end 2.249932 2.249932)
			(stroke
				(width 0.1)
				(type default)
			)
			(layer "F.Fab")
		)
		(fp_line
			(start 2.249932 2.249932)
			(end -2.249932 2.249932)
			(stroke
				(width 0.1)
				(type default)
			)
			(layer "F.Fab")
		)
		(pad "1" smd rect
			(at -1.82499 0)
			(size 1.0668 2.5146)
			(layers "F.Cu" "F.Mask" "F.Paste")
			(net "P0V9_CPU1_RT_2D")
		)
		(pad "2" smd rect
			(at 1.82499 0)
			(size 1.0668 2.5146)
			(layers "F.Cu" "F.Mask" "F.Paste")
			(net "P0V9_CPU1_RT1_2A")
		)
	)
	(footprint ""
		(layer "F.Cu")
		(at 178.689 -405.511 180)
		(property "Reference" "PC2192"
			(at 0 0 180)
			(layer "F.SilkS")
			(hide yes)
			(effects
				(font
					(size 1.27 1.27)
				)
			)
		)
		(property "Value" ""
			(at 0 0 180)
			(layer "F.Fab")
			(effects
				(font
					(size 1.27 1.27)
				)
			)
		)
		(duplicate_pad_numbers_are_jumpers no)
		(fp_line
			(start 0.7874 0.4064)
			(end -0.7874 0.4064)
			(stroke
				(width 0.1524)
				(type default)
			)
			(layer "F.SilkS")
		)
		(fp_line
			(start 0.7874 -0.4064)
			(end 0.7874 0.4064)
			(stroke
				(width 0.1524)
				(type default)
			)
			(layer "F.SilkS")
		)
		(fp_line
			(start -0.7874 0.4064)
			(end -0.7874 -0.4064)
			(stroke
				(width 0.1524)
				(type default)
			)
			(layer "F.SilkS")
		)
		(fp_line
			(start -0.7874 -0.4064)
			(end 0.7874 -0.4064)
			(stroke
				(width 0.1524)
				(type default)
			)
			(layer "F.SilkS")
		)
		(fp_line
			(start 0.67945 0.3048)
			(end 0.120396 0.3048)
			(stroke
				(width 0.1)
				(type default)
			)
			(layer "F.Fab")
		)
		(fp_line
			(start 0.67945 -0.3048)
			(end 0.67945 0.3048)
			(stroke
				(width 0.1)
				(type default)
			)
			(layer "F.Fab")
		)
		(fp_line
			(start 0.12065 -0.2794)
			(end 0.12065 -0.3048)
			(stroke
				(width 0.1)
				(type default)
			)
			(layer "F.Fab")
		)
		(fp_line
			(start 0.12065 -0.3048)
			(end 0.67945 -0.3048)
			(stroke
				(width 0.1)
				(type default)
			)
			(layer "F.Fab")
		)
		(fp_line
			(start 0.120396 0.3048)
			(end 0.120396 0.2794)
			(stroke
				(width 0.1)
				(type default)
			)
			(layer "F.Fab")
		)
		(fp_line
			(start 0.120396 0.2794)
			(end -0.12065 0.2794)
			(stroke
				(width 0.1)
				(type default)
			)
			(layer "F.Fab")
		)
		(fp_line
			(start -0.12065 0.3048)
			(end -0.67945 0.3048)
			(stroke
				(width 0.1)
				(type default)
			)
			(layer "F.Fab")
		)
		(fp_line
			(start -0.12065 0.2794)
			(end -0.12065 0.3048)
			(stroke
				(width 0.1)
				(type default)
			)
			(layer "F.Fab")
		)
		(fp_line
			(start -0.12065 -0.2794)
			(end 0.12065 -0.2794)
			(stroke
				(width 0.1)
				(type default)
			)
			(layer "F.Fab")
		)
		(fp_line
			(start -0.12065 -0.305054)
			(end -0.12065 -0.2794)
			(stroke
				(width 0.1)
				(type default)
			)
			(layer "F.Fab")
		)
		(fp_line
			(start -0.67945 0.3048)
			(end -0.67945 -0.305054)
			(stroke
				(width 0.1)
				(type default)
			)
			(layer "F.Fab")
		)
		(fp_line
			(start -0.67945 -0.305054)
			(end -0.12065 -0.305054)
			(stroke
				(width 0.1)
				(type default)
			)
			(layer "F.Fab")
		)
		(pad "1" smd circle
			(at -0.40005 0 180)
			(size 0 0)
			(layers "F.Cu" "F.Mask" "F.Paste")
			(net "HSC_VTEMP")
		)
		(pad "2" smd circle
			(at 0.40005 0 180)
			(size 0 0)
			(layers "F.Cu" "F.Mask" "F.Paste")
			(net "AGND_HSC")
		)
	)
	(footprint ""
		(layer "F.Cu")
		(at 389.653018 -404.0124 -90)
		(property "Reference" "R1123"
			(at 0 0 270)
			(layer "F.SilkS")
			(hide yes)
			(effects
				(font
					(size 1.27 1.27)
				)
			)
		)
		(property "Value" ""
			(at 0 0 270)
			(layer "F.Fab")
			(effects
				(font
					(size 1.27 1.27)
				)
			)
		)
		(duplicate_pad_numbers_are_jumpers no)
		(fp_line
			(start -0.32512 0.175006)
			(end -0.32512 -0.175006)
			(stroke
				(width 0.1)
				(type default)
			)
			(layer "F.Fab")
		)
		(fp_line
			(start 0.32512 0.175006)
			(end -0.32512 0.175006)
			(stroke
				(width 0.1)
				(type default)
			)
			(layer "F.Fab")
		)
		(fp_line
			(start -0.32512 -0.175006)
			(end 0.32512 -0.175006)
			(stroke
				(width 0.1)
				(type default)
			)
			(layer "F.Fab")
		)
		(fp_line
			(start 0.32512 -0.175006)
			(end 0.32512 0.175006)
			(stroke
				(width 0.1)
				(type default)
			)
			(layer "F.Fab")
		)
		(pad "1" smd rect
			(at -0.2667 0 270)
			(size 0.3048 0.381)
			(layers "F.Cu" "F.Mask" "F.Paste")
			(net "P1V8_CPU0_RT_1D")
		)
		(pad "2" smd rect
			(at 0.2667 0 90)
			(size 0.3048 0.381)
			(layers "F.Cu" "F.Mask" "F.Paste")
			(net "RT_CPU0_P3_VQPS")
		)
	)
)
